(kicad_sch (version 20230121) (generator eeschema)

  (paper "A3")

  (title_block
    (title "Thunderbolt PCIe Adaper")
    (date "2024-07-09")
    (rev "1.0.3")
    (comment 1 "www.antmicro.com")
    (comment 2 "Antmicro Ltd.")
  )

  (junction (at 290.83 118.11) (diameter 0) (color 0 0 0 0)
  )
  (junction (at 294.64 115.57) (diameter 0) (color 0 0 0 0)
  )
  (junction (at 294.64 133.35) (diameter 0) (color 0 0 0 0)
  )
  (junction (at 294.64 153.67) (diameter 0) (color 0 0 0 0)
  )
  (junction (at 30.48 270.51) (diameter 0) (color 0 0 0 0)
  )
  (junction (at 294.64 102.87) (diameter 0) (color 0 0 0 0)
  )
  (junction (at 294.64 173.99) (diameter 0) (color 0 0 0 0)
  )
  (junction (at 294.64 146.05) (diameter 0) (color 0 0 0 0)
  )
  (junction (at 331.47 138.43) (diameter 0) (color 0 0 0 0)
  )
  (junction (at 331.47 151.13) (diameter 0) (color 0 0 0 0)
  )
  (junction (at 201.93 163.83) (diameter 0) (color 0 0 0 0)
  )
  (junction (at 331.47 102.87) (diameter 0) (color 0 0 0 0)
  )
  (junction (at 30.48 276.86) (diameter 0) (color 0 0 0 0)
  )
  (junction (at 331.47 146.05) (diameter 0) (color 0 0 0 0)
  )
  (junction (at 336.55 120.65) (diameter 0) (color 0 0 0 0)
  )
  (junction (at 331.47 130.81) (diameter 0) (color 0 0 0 0)
  )
  (junction (at 294.64 140.97) (diameter 0) (color 0 0 0 0)
  )
  (junction (at 201.93 170.18) (diameter 0) (color 0 0 0 0)
  )
  (junction (at 331.47 161.29) (diameter 0) (color 0 0 0 0)
  )
  (junction (at 331.47 168.91) (diameter 0) (color 0 0 0 0)
  )
  (junction (at 101.6 130.81) (diameter 0) (color 0 0 0 0)
  )
  (junction (at 331.47 158.75) (diameter 0) (color 0 0 0 0)
  )
  (junction (at 294.64 166.37) (diameter 0) (color 0 0 0 0)
  )
  (junction (at 294.64 181.61) (diameter 0) (color 0 0 0 0)
  )
  (junction (at 294.64 163.83) (diameter 0) (color 0 0 0 0)
  )
  (junction (at 294.64 100.33) (diameter 0) (color 0 0 0 0)
  )
  (junction (at 331.47 179.07) (diameter 0) (color 0 0 0 0)
  )
  (junction (at 368.3 125.73) (diameter 0) (color 0 0 0 0)
  )
  (junction (at 331.47 171.45) (diameter 0) (color 0 0 0 0)
  )
  (junction (at 294.64 156.21) (diameter 0) (color 0 0 0 0)
  )

  (no_connect (at 297.18 110.49))
  (no_connect (at 297.18 176.53))
  (no_connect (at 297.18 143.51))
  (no_connect (at 330.2 110.49))
  (no_connect (at 330.2 181.61))
  (no_connect (at 297.18 113.03))
  (no_connect (at 297.18 130.81))
  (no_connect (at 330.2 100.33))
  (no_connect (at 297.18 179.07))
  (no_connect (at 330.2 113.03))
  (no_connect (at 297.18 120.65))
  (no_connect (at 330.2 115.57))
  (no_connect (at 330.2 148.59))
  (no_connect (at 330.2 118.11))

  (wire (pts (xy 294.64 133.35) (xy 294.64 140.97))
    (stroke (width 0) (type default))
  )
  (wire (pts (xy 330.2 173.99) (xy 340.36 173.99))
    (stroke (width 0) (type default))
  )
  (wire (pts (xy 190.5 200.66) (xy 190.5 203.2))
    (stroke (width 0) (type default))
  )
  (wire (pts (xy 330.2 102.87) (xy 331.47 102.87))
    (stroke (width 0) (type default))
  )
  (wire (pts (xy 283.21 99.06) (xy 283.21 100.33))
    (stroke (width 0) (type default))
  )
  (wire (pts (xy 294.64 102.87) (xy 297.18 102.87))
    (stroke (width 0) (type default))
  )
  (wire (pts (xy 285.75 171.45) (xy 297.18 171.45))
    (stroke (width 0) (type default))
  )
  (wire (pts (xy 285.75 158.75) (xy 297.18 158.75))
    (stroke (width 0) (type default))
  )
  (wire (pts (xy 294.64 107.95) (xy 294.64 115.57))
    (stroke (width 0) (type default))
  )
  (wire (pts (xy 297.18 140.97) (xy 294.64 140.97))
    (stroke (width 0) (type default))
  )
  (wire (pts (xy 331.47 168.91) (xy 331.47 171.45))
    (stroke (width 0) (type default))
  )
  (wire (pts (xy 330.2 130.81) (xy 331.47 130.81))
    (stroke (width 0) (type default))
  )
  (wire (pts (xy 294.64 156.21) (xy 294.64 163.83))
    (stroke (width 0) (type default))
  )
  (wire (pts (xy 201.93 102.87) (xy 207.01 102.87))
    (stroke (width 0) (type default))
  )
  (wire (pts (xy 290.83 118.11) (xy 290.83 123.19))
    (stroke (width 0) (type default))
  )
  (wire (pts (xy 330.2 179.07) (xy 331.47 179.07))
    (stroke (width 0) (type default))
  )
  (wire (pts (xy 368.3 133.35) (xy 368.3 134.62))
    (stroke (width 0) (type default))
  )
  (wire (pts (xy 331.47 171.45) (xy 331.47 179.07))
    (stroke (width 0) (type default))
  )
  (wire (pts (xy 330.2 125.73) (xy 368.3 125.73))
    (stroke (width 0) (type default))
  )
  (wire (pts (xy 331.47 146.05) (xy 331.47 151.13))
    (stroke (width 0) (type default))
  )
  (wire (pts (xy 184.15 200.66) (xy 184.15 203.2))
    (stroke (width 0) (type default))
  )
  (wire (pts (xy 285.75 148.59) (xy 297.18 148.59))
    (stroke (width 0) (type default))
  )
  (wire (pts (xy 31.75 276.86) (xy 30.48 276.86))
    (stroke (width 0) (type default))
  )
  (wire (pts (xy 330.2 163.83) (xy 340.36 163.83))
    (stroke (width 0) (type default))
  )
  (wire (pts (xy 196.85 200.66) (xy 196.85 203.2))
    (stroke (width 0) (type default))
  )
  (wire (pts (xy 294.64 102.87) (xy 294.64 105.41))
    (stroke (width 0) (type default))
  )
  (wire (pts (xy 203.2 200.66) (xy 203.2 203.2))
    (stroke (width 0) (type default))
  )
  (wire (pts (xy 331.47 130.81) (xy 331.47 138.43))
    (stroke (width 0) (type default))
  )
  (wire (pts (xy 201.93 113.03) (xy 207.01 113.03))
    (stroke (width 0) (type default))
  )
  (wire (pts (xy 190.5 208.28) (xy 190.5 210.82))
    (stroke (width 0) (type default))
  )
  (wire (pts (xy 330.2 120.65) (xy 336.55 120.65))
    (stroke (width 0) (type default))
  )
  (wire (pts (xy 368.3 125.73) (xy 368.3 128.27))
    (stroke (width 0) (type default))
  )
  (wire (pts (xy 331.47 179.07) (xy 331.47 187.96))
    (stroke (width 0) (type default))
  )
  (wire (pts (xy 294.64 100.33) (xy 294.64 102.87))
    (stroke (width 0) (type default))
  )
  (wire (pts (xy 285.75 168.91) (xy 297.18 168.91))
    (stroke (width 0) (type default))
  )
  (wire (pts (xy 331.47 161.29) (xy 331.47 168.91))
    (stroke (width 0) (type default))
  )
  (wire (pts (xy 201.93 163.83) (xy 201.93 170.18))
    (stroke (width 0) (type default))
  )
  (wire (pts (xy 336.55 120.65) (xy 340.36 120.65))
    (stroke (width 0) (type default))
  )
  (wire (pts (xy 330.2 176.53) (xy 340.36 176.53))
    (stroke (width 0) (type default))
  )
  (wire (pts (xy 196.85 208.28) (xy 196.85 210.82))
    (stroke (width 0) (type default))
  )
  (wire (pts (xy 331.47 151.13) (xy 331.47 158.75))
    (stroke (width 0) (type default))
  )
  (wire (pts (xy 330.2 146.05) (xy 331.47 146.05))
    (stroke (width 0) (type default))
  )
  (wire (pts (xy 297.18 133.35) (xy 294.64 133.35))
    (stroke (width 0) (type default))
  )
  (wire (pts (xy 101.6 129.54) (xy 101.6 130.81))
    (stroke (width 0) (type default))
  )
  (wire (pts (xy 201.93 153.67) (xy 205.74 153.67))
    (stroke (width 0) (type default))
  )
  (wire (pts (xy 297.18 163.83) (xy 294.64 163.83))
    (stroke (width 0) (type default))
  )
  (wire (pts (xy 294.64 100.33) (xy 297.18 100.33))
    (stroke (width 0) (type default))
  )
  (wire (pts (xy 285.75 161.29) (xy 297.18 161.29))
    (stroke (width 0) (type default))
  )
  (wire (pts (xy 201.93 97.79) (xy 207.01 97.79))
    (stroke (width 0) (type default))
  )
  (wire (pts (xy 294.64 163.83) (xy 294.64 166.37))
    (stroke (width 0) (type default))
  )
  (wire (pts (xy 297.18 166.37) (xy 294.64 166.37))
    (stroke (width 0) (type default))
  )
  (wire (pts (xy 294.64 99.06) (xy 294.64 100.33))
    (stroke (width 0) (type default))
  )
  (wire (pts (xy 201.93 105.41) (xy 207.01 105.41))
    (stroke (width 0) (type default))
  )
  (wire (pts (xy 101.6 130.81) (xy 105.41 130.81))
    (stroke (width 0) (type default))
  )
  (wire (pts (xy 201.93 170.18) (xy 201.93 173.99))
    (stroke (width 0) (type default))
  )
  (wire (pts (xy 331.47 99.06) (xy 331.47 102.87))
    (stroke (width 0) (type default))
  )
  (wire (pts (xy 30.48 276.86) (xy 30.48 279.4))
    (stroke (width 0) (type default))
  )
  (wire (pts (xy 85.09 135.89) (xy 85.09 133.35))
    (stroke (width 0) (type default))
  )
  (wire (pts (xy 330.2 123.19) (xy 336.55 123.19))
    (stroke (width 0) (type default))
  )
  (wire (pts (xy 368.3 125.73) (xy 373.38 125.73))
    (stroke (width 0) (type default))
  )
  (wire (pts (xy 330.2 140.97) (xy 340.36 140.97))
    (stroke (width 0) (type default))
  )
  (wire (pts (xy 201.93 133.35) (xy 207.01 133.35))
    (stroke (width 0) (type default))
  )
  (wire (pts (xy 331.47 105.41) (xy 330.2 105.41))
    (stroke (width 0) (type default))
  )
  (wire (pts (xy 201.93 161.29) (xy 201.93 163.83))
    (stroke (width 0) (type default))
  )
  (wire (pts (xy 331.47 158.75) (xy 331.47 161.29))
    (stroke (width 0) (type default))
  )
  (wire (pts (xy 294.64 166.37) (xy 294.64 173.99))
    (stroke (width 0) (type default))
  )
  (wire (pts (xy 283.21 105.41) (xy 283.21 107.95))
    (stroke (width 0) (type default))
  )
  (wire (pts (xy 297.18 146.05) (xy 294.64 146.05))
    (stroke (width 0) (type default))
  )
  (wire (pts (xy 330.2 133.35) (xy 340.36 133.35))
    (stroke (width 0) (type default))
  )
  (wire (pts (xy 285.75 138.43) (xy 297.18 138.43))
    (stroke (width 0) (type default))
  )
  (wire (pts (xy 82.55 130.81) (xy 101.6 130.81))
    (stroke (width 0) (type default))
  )
  (wire (pts (xy 85.09 133.35) (xy 82.55 133.35))
    (stroke (width 0) (type default))
  )
  (wire (pts (xy 290.83 123.19) (xy 297.18 123.19))
    (stroke (width 0) (type default))
  )
  (wire (pts (xy 30.48 270.51) (xy 30.48 276.86))
    (stroke (width 0) (type default))
  )
  (wire (pts (xy 294.64 173.99) (xy 294.64 181.61))
    (stroke (width 0) (type default))
  )
  (wire (pts (xy 297.18 173.99) (xy 294.64 173.99))
    (stroke (width 0) (type default))
  )
  (wire (pts (xy 330.2 135.89) (xy 340.36 135.89))
    (stroke (width 0) (type default))
  )
  (wire (pts (xy 344.17 99.06) (xy 344.17 100.33))
    (stroke (width 0) (type default))
  )
  (wire (pts (xy 297.18 115.57) (xy 294.64 115.57))
    (stroke (width 0) (type default))
  )
  (wire (pts (xy 297.18 181.61) (xy 294.64 181.61))
    (stroke (width 0) (type default))
  )
  (wire (pts (xy 201.93 125.73) (xy 207.01 125.73))
    (stroke (width 0) (type default))
  )
  (wire (pts (xy 294.64 115.57) (xy 294.64 133.35))
    (stroke (width 0) (type default))
  )
  (wire (pts (xy 285.75 135.89) (xy 297.18 135.89))
    (stroke (width 0) (type default))
  )
  (wire (pts (xy 294.64 140.97) (xy 294.64 146.05))
    (stroke (width 0) (type default))
  )
  (wire (pts (xy 330.2 107.95) (xy 331.47 107.95))
    (stroke (width 0) (type default))
  )
  (wire (pts (xy 285.75 151.13) (xy 297.18 151.13))
    (stroke (width 0) (type default))
  )
  (wire (pts (xy 330.2 168.91) (xy 331.47 168.91))
    (stroke (width 0) (type default))
  )
  (wire (pts (xy 201.93 123.19) (xy 207.01 123.19))
    (stroke (width 0) (type default))
  )
  (wire (pts (xy 201.93 115.57) (xy 207.01 115.57))
    (stroke (width 0) (type default))
  )
  (wire (pts (xy 203.2 208.28) (xy 203.2 210.82))
    (stroke (width 0) (type default))
  )
  (wire (pts (xy 330.2 153.67) (xy 340.36 153.67))
    (stroke (width 0) (type default))
  )
  (wire (pts (xy 331.47 102.87) (xy 331.47 105.41))
    (stroke (width 0) (type default))
  )
  (wire (pts (xy 285.75 118.11) (xy 290.83 118.11))
    (stroke (width 0) (type default))
  )
  (wire (pts (xy 201.93 156.21) (xy 205.74 156.21))
    (stroke (width 0) (type default))
  )
  (wire (pts (xy 330.2 158.75) (xy 331.47 158.75))
    (stroke (width 0) (type default))
  )
  (wire (pts (xy 201.93 138.43) (xy 207.01 138.43))
    (stroke (width 0) (type default))
  )
  (wire (pts (xy 285.75 125.73) (xy 297.18 125.73))
    (stroke (width 0) (type default))
  )
  (wire (pts (xy 201.93 118.11) (xy 207.01 118.11))
    (stroke (width 0) (type default))
  )
  (wire (pts (xy 184.15 208.28) (xy 184.15 210.82))
    (stroke (width 0) (type default))
  )
  (wire (pts (xy 330.2 156.21) (xy 340.36 156.21))
    (stroke (width 0) (type default))
  )
  (wire (pts (xy 297.18 153.67) (xy 294.64 153.67))
    (stroke (width 0) (type default))
  )
  (wire (pts (xy 290.83 118.11) (xy 297.18 118.11))
    (stroke (width 0) (type default))
  )
  (wire (pts (xy 294.64 153.67) (xy 294.64 156.21))
    (stroke (width 0) (type default))
  )
  (wire (pts (xy 330.2 151.13) (xy 331.47 151.13))
    (stroke (width 0) (type default))
  )
  (wire (pts (xy 297.18 156.21) (xy 294.64 156.21))
    (stroke (width 0) (type default))
  )
  (wire (pts (xy 330.2 161.29) (xy 331.47 161.29))
    (stroke (width 0) (type default))
  )
  (wire (pts (xy 201.93 110.49) (xy 207.01 110.49))
    (stroke (width 0) (type default))
  )
  (wire (pts (xy 30.48 264.16) (xy 30.48 270.51))
    (stroke (width 0) (type default))
  )
  (wire (pts (xy 330.2 171.45) (xy 331.47 171.45))
    (stroke (width 0) (type default))
  )
  (wire (pts (xy 294.64 146.05) (xy 294.64 153.67))
    (stroke (width 0) (type default))
  )
  (wire (pts (xy 344.17 105.41) (xy 344.17 107.95))
    (stroke (width 0) (type default))
  )
  (wire (pts (xy 336.55 123.19) (xy 336.55 120.65))
    (stroke (width 0) (type default))
  )
  (wire (pts (xy 201.93 130.81) (xy 207.01 130.81))
    (stroke (width 0) (type default))
  )
  (wire (pts (xy 331.47 138.43) (xy 331.47 146.05))
    (stroke (width 0) (type default))
  )
  (wire (pts (xy 30.48 264.16) (xy 31.75 264.16))
    (stroke (width 0) (type default))
  )
  (wire (pts (xy 297.18 107.95) (xy 294.64 107.95))
    (stroke (width 0) (type default))
  )
  (wire (pts (xy 330.2 166.37) (xy 340.36 166.37))
    (stroke (width 0) (type default))
  )
  (wire (pts (xy 297.18 105.41) (xy 294.64 105.41))
    (stroke (width 0) (type default))
  )
  (wire (pts (xy 201.93 148.59) (xy 207.01 148.59))
    (stroke (width 0) (type default))
  )
  (wire (pts (xy 201.93 140.97) (xy 207.01 140.97))
    (stroke (width 0) (type default))
  )
  (wire (pts (xy 201.93 146.05) (xy 207.01 146.05))
    (stroke (width 0) (type default))
  )
  (wire (pts (xy 294.64 181.61) (xy 294.64 187.96))
    (stroke (width 0) (type default))
  )
  (wire (pts (xy 201.93 170.18) (xy 203.2 170.18))
    (stroke (width 0) (type default))
  )
  (wire (pts (xy 331.47 107.95) (xy 331.47 130.81))
    (stroke (width 0) (type default))
  )
  (wire (pts (xy 31.75 270.51) (xy 30.48 270.51))
    (stroke (width 0) (type default))
  )
  (wire (pts (xy 330.2 138.43) (xy 331.47 138.43))
    (stroke (width 0) (type default))
  )
  (wire (pts (xy 330.2 143.51) (xy 340.36 143.51))
    (stroke (width 0) (type default))
  )

  (text "+12V Molex Connector" (at 57.785 114.935 0)
    (effects (font (size 2.54 2.54) bold) (justify left bottom))
  )
  (text "PCI Express Connector" (at 290.83 77.47 0)
    (effects (font (size 2.54 2.54) bold) (justify left bottom))
  )
  (text "USB-C Connector" (at 177.8 83.82 0)
    (effects (font (size 2.54 2.54) bold) (justify left bottom))
  )

  (global_label "PCIE_RX1_P" (shape input) (at 340.36 153.67 0) (fields_autoplaced)
    (effects (font (size 1.27 1.27)) (justify left))
    (property "Intersheetrefs" "${INTERSHEET_REFS}" (at 353.9612 153.5906 0)
      (effects (font (size 1.27 1.27)) (justify left) hide)
    )
  )
  (global_label "PCIE_TX2_N" (shape input) (at 285.75 161.29 180) (fields_autoplaced)
    (effects (font (size 1.27 1.27)) (justify right))
    (property "Intersheetrefs" "${INTERSHEET_REFS}" (at 272.3907 161.2106 0)
      (effects (font (size 1.27 1.27)) (justify right) hide)
    )
  )
  (global_label "PCIE_RX2_P" (shape input) (at 340.36 163.83 0) (fields_autoplaced)
    (effects (font (size 1.27 1.27)) (justify left))
    (property "Intersheetrefs" "${INTERSHEET_REFS}" (at 353.9612 163.7506 0)
      (effects (font (size 1.27 1.27)) (justify left) hide)
    )
  )
  (global_label "TB_RX0_N" (shape input) (at 207.01 125.73 0) (fields_autoplaced)
    (effects (font (size 1.27 1.27)) (justify left))
    (property "Intersheetrefs" "${INTERSHEET_REFS}" (at 218.6155 125.6506 0)
      (effects (font (size 1.27 1.27)) (justify left) hide)
    )
  )
  (global_label "PCIE_RX0_P" (shape input) (at 340.36 140.97 0) (fields_autoplaced)
    (effects (font (size 1.27 1.27)) (justify left))
    (property "Intersheetrefs" "${INTERSHEET_REFS}" (at 353.9612 140.8906 0)
      (effects (font (size 1.27 1.27)) (justify left) hide)
    )
  )
  (global_label "5V0_USB" (shape input) (at 203.2 200.66 90) (fields_autoplaced)
    (effects (font (size 1.27 1.27)) (justify left))
    (property "Intersheetrefs" "${INTERSHEET_REFS}" (at 203.2794 189.9617 90)
      (effects (font (size 1.27 1.27)) (justify left) hide)
    )
  )
  (global_label "CC1" (shape input) (at 207.01 102.87 0) (fields_autoplaced)
    (effects (font (size 1.27 1.27)) (justify left))
    (property "Intersheetrefs" "${INTERSHEET_REFS}" (at 213.1726 102.7906 0)
      (effects (font (size 1.27 1.27)) (justify left) hide)
    )
  )
  (global_label "TB_TX1_N" (shape input) (at 207.01 148.59 0) (fields_autoplaced)
    (effects (font (size 1.27 1.27)) (justify left))
    (property "Intersheetrefs" "${INTERSHEET_REFS}" (at 218.3131 148.5106 0)
      (effects (font (size 1.27 1.27)) (justify left) hide)
    )
  )
  (global_label "USB_T_P" (shape input) (at 207.01 110.49 0) (fields_autoplaced)
    (effects (font (size 1.27 1.27)) (justify left))
    (property "Intersheetrefs" "${INTERSHEET_REFS}" (at 217.406 110.4106 0)
      (effects (font (size 1.27 1.27)) (justify left) hide)
    )
  )
  (global_label "12V0_PCIE" (shape input) (at 283.21 99.06 90) (fields_autoplaced)
    (effects (font (size 1.27 1.27)) (justify left))
    (property "Intersheetrefs" "${INTERSHEET_REFS}" (at 283.2894 86.6683 90)
      (effects (font (size 1.27 1.27)) (justify left) hide)
    )
  )
  (global_label "PCIE_CLK_CON_N" (shape input) (at 340.36 135.89 0) (fields_autoplaced)
    (effects (font (size 1.27 1.27)) (justify left))
    (property "Intersheetrefs" "${INTERSHEET_REFS}" (at 358.7993 135.8106 0)
      (effects (font (size 1.27 1.27)) (justify left) hide)
    )
  )
  (global_label "PCIE_TX0_N" (shape input) (at 285.75 138.43 180) (fields_autoplaced)
    (effects (font (size 1.27 1.27)) (justify right))
    (property "Intersheetrefs" "${INTERSHEET_REFS}" (at 272.3907 138.3506 0)
      (effects (font (size 1.27 1.27)) (justify right) hide)
    )
  )
  (global_label "PCIE_TX1_N" (shape input) (at 285.75 151.13 180) (fields_autoplaced)
    (effects (font (size 1.27 1.27)) (justify right))
    (property "Intersheetrefs" "${INTERSHEET_REFS}" (at 272.3907 151.0506 0)
      (effects (font (size 1.27 1.27)) (justify right) hide)
    )
  )
  (global_label "TB_RX1_P" (shape input) (at 207.01 138.43 0) (fields_autoplaced)
    (effects (font (size 1.27 1.27)) (justify left))
    (property "Intersheetrefs" "${INTERSHEET_REFS}" (at 218.555 138.3506 0)
      (effects (font (size 1.27 1.27)) (justify left) hide)
    )
  )
  (global_label "PCIE_RX3_P" (shape input) (at 340.36 173.99 0) (fields_autoplaced)
    (effects (font (size 1.27 1.27)) (justify left))
    (property "Intersheetrefs" "${INTERSHEET_REFS}" (at 353.9612 173.9106 0)
      (effects (font (size 1.27 1.27)) (justify left) hide)
    )
  )
  (global_label "TB_TX0_P" (shape input) (at 207.01 130.81 0) (fields_autoplaced)
    (effects (font (size 1.27 1.27)) (justify left))
    (property "Intersheetrefs" "${INTERSHEET_REFS}" (at 218.2526 130.7306 0)
      (effects (font (size 1.27 1.27)) (justify left) hide)
    )
  )
  (global_label "PCIE_RX1_N" (shape input) (at 340.36 156.21 0) (fields_autoplaced)
    (effects (font (size 1.27 1.27)) (justify left))
    (property "Intersheetrefs" "${INTERSHEET_REFS}" (at 354.0217 156.1306 0)
      (effects (font (size 1.27 1.27)) (justify left) hide)
    )
  )
  (global_label "PCIE_TX3_P" (shape input) (at 285.75 168.91 180) (fields_autoplaced)
    (effects (font (size 1.27 1.27)) (justify right))
    (property "Intersheetrefs" "${INTERSHEET_REFS}" (at 272.4512 168.8306 0)
      (effects (font (size 1.27 1.27)) (justify right) hide)
    )
  )
  (global_label "SBU1" (shape input) (at 205.74 153.67 0) (fields_autoplaced)
    (effects (font (size 1.27 1.27)) (justify left))
    (property "Intersheetrefs" "${INTERSHEET_REFS}" (at 213.1726 153.5906 0)
      (effects (font (size 1.27 1.27)) (justify left) hide)
    )
  )
  (global_label "TB_TX0_N" (shape input) (at 207.01 133.35 0) (fields_autoplaced)
    (effects (font (size 1.27 1.27)) (justify left))
    (property "Intersheetrefs" "${INTERSHEET_REFS}" (at 218.3131 133.2706 0)
      (effects (font (size 1.27 1.27)) (justify left) hide)
    )
  )
  (global_label "3V3_SYS" (shape input) (at 285.75 118.11 180) (fields_autoplaced)
    (effects (font (size 1.27 1.27)) (justify right))
    (property "Intersheetrefs" "${INTERSHEET_REFS}" (at 275.354 118.1894 0)
      (effects (font (size 1.27 1.27)) (justify right) hide)
    )
  )
  (global_label "3V3_SYS" (shape input) (at 340.36 120.65 0) (fields_autoplaced)
    (effects (font (size 1.27 1.27)) (justify left))
    (property "Intersheetrefs" "${INTERSHEET_REFS}" (at 350.756 120.5706 0)
      (effects (font (size 1.27 1.27)) (justify left) hide)
    )
  )
  (global_label "USB_T_N" (shape input) (at 207.01 113.03 0) (fields_autoplaced)
    (effects (font (size 1.27 1.27)) (justify left))
    (property "Intersheetrefs" "${INTERSHEET_REFS}" (at 217.4664 112.9506 0)
      (effects (font (size 1.27 1.27)) (justify left) hide)
    )
  )
  (global_label "12V0_PCIE" (shape input) (at 331.47 99.06 90) (fields_autoplaced)
    (effects (font (size 1.27 1.27)) (justify left))
    (property "Intersheetrefs" "${INTERSHEET_REFS}" (at 331.5494 86.6683 90)
      (effects (font (size 1.27 1.27)) (justify left) hide)
    )
  )
  (global_label "USB_B_P" (shape input) (at 207.01 115.57 0) (fields_autoplaced)
    (effects (font (size 1.27 1.27)) (justify left))
    (property "Intersheetrefs" "${INTERSHEET_REFS}" (at 217.7083 115.4906 0)
      (effects (font (size 1.27 1.27)) (justify left) hide)
    )
  )
  (global_label "SBU2" (shape input) (at 205.74 156.21 0) (fields_autoplaced)
    (effects (font (size 1.27 1.27)) (justify left))
    (property "Intersheetrefs" "${INTERSHEET_REFS}" (at 213.1726 156.1306 0)
      (effects (font (size 1.27 1.27)) (justify left) hide)
    )
  )
  (global_label "PCIE_CLK_CON_P" (shape input) (at 340.36 133.35 0) (fields_autoplaced)
    (effects (font (size 1.27 1.27)) (justify left))
    (property "Intersheetrefs" "${INTERSHEET_REFS}" (at 358.7388 133.2706 0)
      (effects (font (size 1.27 1.27)) (justify left) hide)
    )
  )
  (global_label "5V0_USB" (shape input) (at 184.15 200.66 90) (fields_autoplaced)
    (effects (font (size 1.27 1.27)) (justify left))
    (property "Intersheetrefs" "${INTERSHEET_REFS}" (at 184.2294 189.9617 90)
      (effects (font (size 1.27 1.27)) (justify left) hide)
    )
  )
  (global_label "12V0_PCIE" (shape input) (at 294.64 99.06 90) (fields_autoplaced)
    (effects (font (size 1.27 1.27)) (justify left))
    (property "Intersheetrefs" "${INTERSHEET_REFS}" (at 294.7194 86.6683 90)
      (effects (font (size 1.27 1.27)) (justify left) hide)
    )
  )
  (global_label "5V0_USB" (shape input) (at 207.01 97.79 0) (fields_autoplaced)
    (effects (font (size 1.27 1.27)) (justify left))
    (property "Intersheetrefs" "${INTERSHEET_REFS}" (at 217.7083 97.7106 0)
      (effects (font (size 1.27 1.27)) (justify left) hide)
    )
  )
  (global_label "PCIE_RX0_N" (shape input) (at 340.36 143.51 0) (fields_autoplaced)
    (effects (font (size 1.27 1.27)) (justify left))
    (property "Intersheetrefs" "${INTERSHEET_REFS}" (at 354.0217 143.4306 0)
      (effects (font (size 1.27 1.27)) (justify left) hide)
    )
  )
  (global_label "PCIE_TX2_P" (shape input) (at 285.75 158.75 180) (fields_autoplaced)
    (effects (font (size 1.27 1.27)) (justify right))
    (property "Intersheetrefs" "${INTERSHEET_REFS}" (at 272.4512 158.6706 0)
      (effects (font (size 1.27 1.27)) (justify right) hide)
    )
  )
  (global_label "12V0_MOLEX" (shape input) (at 105.41 130.81 0) (fields_autoplaced)
    (effects (font (size 1.27 1.27)) (justify left))
    (property "Intersheetrefs" "${INTERSHEET_REFS}" (at 119.6764 130.7306 0)
      (effects (font (size 1.27 1.27)) (justify left) hide)
    )
  )
  (global_label "USB_B_N" (shape input) (at 207.01 118.11 0) (fields_autoplaced)
    (effects (font (size 1.27 1.27)) (justify left))
    (property "Intersheetrefs" "${INTERSHEET_REFS}" (at 217.7688 118.0306 0)
      (effects (font (size 1.27 1.27)) (justify left) hide)
    )
  )
  (global_label "PCIE_TX0_P" (shape input) (at 285.75 135.89 180) (fields_autoplaced)
    (effects (font (size 1.27 1.27)) (justify right))
    (property "Intersheetrefs" "${INTERSHEET_REFS}" (at 272.4512 135.8106 0)
      (effects (font (size 1.27 1.27)) (justify right) hide)
    )
  )
  (global_label "PCIE_WAKE" (shape input) (at 285.75 125.73 180) (fields_autoplaced)
    (effects (font (size 1.27 1.27)) (justify right))
    (property "Intersheetrefs" "${INTERSHEET_REFS}" (at 273.1164 125.6506 0)
      (effects (font (size 1.27 1.27)) (justify right) hide)
    )
  )
  (global_label "PCIE_RX2_N" (shape input) (at 340.36 166.37 0) (fields_autoplaced)
    (effects (font (size 1.27 1.27)) (justify left))
    (property "Intersheetrefs" "${INTERSHEET_REFS}" (at 354.0217 166.2906 0)
      (effects (font (size 1.27 1.27)) (justify left) hide)
    )
  )
  (global_label "PCIE_TX3_N" (shape input) (at 285.75 171.45 180) (fields_autoplaced)
    (effects (font (size 1.27 1.27)) (justify right))
    (property "Intersheetrefs" "${INTERSHEET_REFS}" (at 272.3907 171.3706 0)
      (effects (font (size 1.27 1.27)) (justify right) hide)
    )
  )
  (global_label "TB_RX1_N" (shape input) (at 207.01 140.97 0) (fields_autoplaced)
    (effects (font (size 1.27 1.27)) (justify left))
    (property "Intersheetrefs" "${INTERSHEET_REFS}" (at 218.6155 140.8906 0)
      (effects (font (size 1.27 1.27)) (justify left) hide)
    )
  )
  (global_label "TB_RX0_P" (shape input) (at 207.01 123.19 0) (fields_autoplaced)
    (effects (font (size 1.27 1.27)) (justify left))
    (property "Intersheetrefs" "${INTERSHEET_REFS}" (at 218.555 123.1106 0)
      (effects (font (size 1.27 1.27)) (justify left) hide)
    )
  )
  (global_label "5V0_USB" (shape input) (at 190.5 200.66 90) (fields_autoplaced)
    (effects (font (size 1.27 1.27)) (justify left))
    (property "Intersheetrefs" "${INTERSHEET_REFS}" (at 190.5794 189.9617 90)
      (effects (font (size 1.27 1.27)) (justify left) hide)
    )
  )
  (global_label "TB_TX1_P" (shape input) (at 207.01 146.05 0) (fields_autoplaced)
    (effects (font (size 1.27 1.27)) (justify left))
    (property "Intersheetrefs" "${INTERSHEET_REFS}" (at 218.2526 145.9706 0)
      (effects (font (size 1.27 1.27)) (justify left) hide)
    )
  )
  (global_label "PCIE_TX1_P" (shape input) (at 285.75 148.59 180) (fields_autoplaced)
    (effects (font (size 1.27 1.27)) (justify right))
    (property "Intersheetrefs" "${INTERSHEET_REFS}" (at 272.4512 148.5106 0)
      (effects (font (size 1.27 1.27)) (justify right) hide)
    )
  )
  (global_label "PCIE_RX3_N" (shape input) (at 340.36 176.53 0) (fields_autoplaced)
    (effects (font (size 1.27 1.27)) (justify left))
    (property "Intersheetrefs" "${INTERSHEET_REFS}" (at 354.0217 176.4506 0)
      (effects (font (size 1.27 1.27)) (justify left) hide)
    )
  )
  (global_label "PCIE_PWRGD" (shape input) (at 373.38 125.73 0) (fields_autoplaced)
    (effects (font (size 1.27 1.27)) (justify left))
    (property "Intersheetrefs" "${INTERSHEET_REFS}" (at 387.586 125.6506 0)
      (effects (font (size 1.27 1.27)) (justify left) hide)
    )
  )
  (global_label "5V0_USB" (shape input) (at 196.85 200.66 90) (fields_autoplaced)
    (effects (font (size 1.27 1.27)) (justify left))
    (property "Intersheetrefs" "${INTERSHEET_REFS}" (at 196.9294 189.9617 90)
      (effects (font (size 1.27 1.27)) (justify left) hide)
    )
  )
  (global_label "CC2" (shape input) (at 207.01 105.41 0) (fields_autoplaced)
    (effects (font (size 1.27 1.27)) (justify left))
    (property "Intersheetrefs" "${INTERSHEET_REFS}" (at 213.1726 105.3306 0)
      (effects (font (size 1.27 1.27)) (justify left) hide)
    )
  )
  (global_label "12V0_PCIE" (shape input) (at 344.17 99.06 90) (fields_autoplaced)
    (effects (font (size 1.27 1.27)) (justify left))
    (property "Intersheetrefs" "${INTERSHEET_REFS}" (at 344.2494 86.6683 90)
      (effects (font (size 1.27 1.27)) (justify left) hide)
    )
  )

  (symbol (lib_id "antmicropower:GND") (at 283.21 107.95 0) (unit 1)
    (in_bom yes) (on_board yes) (dnp no) (fields_autoplaced)
    (property "Reference" "#PWR01" (at 283.21 114.3 0)
      (effects (font (size 1.27 1.27)) hide)
    )
    (property "Value" "GND" (at 281.305 112.395 0)
      (effects (font (size 1.27 1.27) (thickness 0.15)) (justify left bottom))
    )
    (property "Footprint" "" (at 283.21 107.95 0)
      (effects (font (size 1.27 1.27) (thickness 0.15)) (justify left bottom) hide)
    )
    (property "Datasheet" "" (at 283.21 107.95 0)
      (effects (font (size 1.27 1.27) (thickness 0.15)) (justify left bottom) hide)
    )
    (property "Author" "Antmicro" (at 292.1 115.57 0)
      (effects (font (size 1.27 1.27) (thickness 0.15)) (justify left bottom) hide)
    )
    (property "License" "Apache-2.0" (at 292.1 118.11 0)
      (effects (font (size 1.27 1.27) (thickness 0.15)) (justify left bottom) hide)
    )
    (pin "1")
    (instances
      (project "thunderbolt-pcie-adapter"
        (path ""
          (reference "#PWR01") (unit 1)
        )
      )
    )
  )

  (symbol (lib_id "antmicropower:GND") (at 190.5 210.82 0) (unit 1)
    (in_bom yes) (on_board yes) (dnp no)
    (property "Reference" "#PWR06" (at 190.5 217.17 0)
      (effects (font (size 1.27 1.27)) hide)
    )
    (property "Value" "GND" (at 188.595 215.265 0)
      (effects (font (size 1.27 1.27) (thickness 0.15)) (justify left bottom))
    )
    (property "Footprint" "" (at 190.5 210.82 0)
      (effects (font (size 1.27 1.27) (thickness 0.15)) (justify left bottom) hide)
    )
    (property "Datasheet" "" (at 190.5 210.82 0)
      (effects (font (size 1.27 1.27) (thickness 0.15)) (justify left bottom) hide)
    )
    (property "Author" "Antmicro" (at 199.39 218.44 0)
      (effects (font (size 1.27 1.27) (thickness 0.15)) (justify left bottom) hide)
    )
    (property "License" "Apache-2.0" (at 199.39 220.98 0)
      (effects (font (size 1.27 1.27) (thickness 0.15)) (justify left bottom) hide)
    )
    (pin "1")
    (instances
      (project "thunderbolt-pcie-adapter"
        (path ""
          (reference "#PWR06") (unit 1)
        )
      )
    )
  )

  (symbol (lib_id "antmicroMechanicalParts:MP_Pad6mm_Drill3mm") (at 31.75 264.16 0) (unit 1)
    (in_bom no) (on_board yes) (dnp no)
    (property "Reference" "MP1" (at 40.64 262.89 0)
      (effects (font (size 1.27 1.27) (thickness 0.15)) (justify left))
    )
    (property "Value" "MP_Pad6mm_Drill3mm" (at 40.64 265.43 0)
      (effects (font (size 1.27 1.27) (thickness 0.15)) (justify left))
    )
    (property "Footprint" "antmicro-footprints:MP_Pad6mm_Drill3mm" (at 52.07 271.78 0)
      (effects (font (size 1.27 1.27) (thickness 0.15)) (justify left bottom) hide)
    )
    (property "Datasheet" "" (at 48.59 279.73 0)
      (effects (font (size 1.27 1.27) (thickness 0.15)) (justify left bottom) hide)
    )
    (property "Author" "Antmicro" (at 52.07 274.32 0)
      (effects (font (size 1.27 1.27) (thickness 0.15)) (justify left bottom) hide)
    )
    (property "License" "Apache-2.0" (at 52.07 276.86 0)
      (effects (font (size 1.27 1.27) (thickness 0.15)) (justify left bottom) hide)
    )
    (pin "1")
    (instances
      (project "thunderbolt-pcie-adapter"
        (path ""
          (reference "MP1") (unit 1)
        )
      )
    )
  )

  (symbol (lib_id "antmicroCapacitorsmisc:C_10u_0805_35V") (at 344.17 105.41 90) (unit 1)
    (in_bom yes) (on_board yes) (dnp no) (fields_autoplaced)
    (property "Reference" "C6" (at 346.075 101.6 90)
      (effects (font (size 1.27 1.27) (thickness 0.15)) (justify right))
    )
    (property "Value" "C_10u_0805_35V" (at 354.33 85.09 0)
      (effects (font (size 1.27 1.27) (thickness 0.15)) (justify left bottom) hide)
    )
    (property "Footprint" "antmicro-footprints:C_0805_2012Metric" (at 356.87 85.09 0)
      (effects (font (size 1.27 1.27) (thickness 0.15)) (justify left bottom) hide)
    )
    (property "Datasheet" "https://www.murata.com/products/productdetail?partno=GRM21BR6YA106KE43%23" (at 359.41 85.09 0)
      (effects (font (size 1.27 1.27) (thickness 0.15)) (justify left bottom) hide)
    )
    (property "MPN" "GRM21BR6YA106KE43L" (at 361.95 85.09 0)
      (effects (font (size 1.27 1.27) (thickness 0.15)) (justify left bottom) hide)
    )
    (property "Manufacturer" "Murata" (at 364.49 85.09 0)
      (effects (font (size 1.27 1.27) (thickness 0.15)) (justify left bottom) hide)
    )
    (property "License" "Apache-2.0" (at 367.03 85.09 0)
      (effects (font (size 1.27 1.27) (thickness 0.15)) (justify left bottom) hide)
    )
    (property "Val" "10u" (at 349.885 102.87 90)
      (effects (font (size 1.27 1.27) (thickness 0.15)) (justify left bottom))
    )
    (property "Voltage" "35V" (at 372.11 85.09 0)
      (effects (font (size 1.27 1.27)) (justify left bottom) hide)
    )
    (property "Dielectric" "" (at 374.65 85.09 0)
      (effects (font (size 1.27 1.27)) (justify left bottom) hide)
    )
    (property "Author" "Antmicro" (at 369.57 85.09 0)
      (effects (font (size 1.27 1.27) (thickness 0.15)) (justify left bottom) hide)
    )
    (pin "1")
    (pin "2")
    (instances
      (project "thunderbolt-pcie-adapter"
        (path ""
          (reference "C6") (unit 1)
        )
      )
    )
  )

  (symbol (lib_id "antmicropower:GND") (at 294.64 187.96 0) (unit 1)
    (in_bom yes) (on_board yes) (dnp no) (fields_autoplaced)
    (property "Reference" "#PWR02" (at 294.64 194.31 0)
      (effects (font (size 1.27 1.27)) hide)
    )
    (property "Value" "GND" (at 292.735 192.405 0)
      (effects (font (size 1.27 1.27) (thickness 0.15)) (justify left bottom))
    )
    (property "Footprint" "" (at 294.64 187.96 0)
      (effects (font (size 1.27 1.27) (thickness 0.15)) (justify left bottom) hide)
    )
    (property "Datasheet" "" (at 294.64 187.96 0)
      (effects (font (size 1.27 1.27) (thickness 0.15)) (justify left bottom) hide)
    )
    (property "Author" "Antmicro" (at 303.53 195.58 0)
      (effects (font (size 1.27 1.27) (thickness 0.15)) (justify left bottom) hide)
    )
    (property "License" "Apache-2.0" (at 303.53 198.12 0)
      (effects (font (size 1.27 1.27) (thickness 0.15)) (justify left bottom) hide)
    )
    (pin "1")
    (instances
      (project "thunderbolt-pcie-adapter"
        (path ""
          (reference "#PWR02") (unit 1)
        )
      )
    )
  )

  (symbol (lib_id "antmicropower:PWR_FLAG") (at 203.2 170.18 270) (unit 1)
    (in_bom yes) (on_board yes) (dnp no) (fields_autoplaced)
    (property "Reference" "#FLG01" (at 205.105 170.18 0)
      (effects (font (size 1.27 1.27)) hide)
    )
    (property "Value" "PWR_FLAG" (at 207.01 170.1799 90)
      (effects (font (size 1.27 1.27)) (justify left))
    )
    (property "Footprint" "" (at 203.2 170.18 0)
      (effects (font (size 1.27 1.27)) hide)
    )
    (property "Datasheet" "" (at 203.2 170.18 0)
      (effects (font (size 1.27 1.27)) hide)
    )
    (pin "1")
    (instances
      (project "thunderbolt-pcie-adapter"
        (path ""
          (reference "#FLG01") (unit 1)
        )
      )
    )
  )

  (symbol (lib_id "antmicroUSBConnectors:USB-C_JAE_DX07S024JJ2") (at 201.93 97.79 0) (unit 1)
    (in_bom yes) (on_board yes) (dnp no)
    (property "Reference" "J1" (at 188.595 90.17 0)
      (effects (font (size 1.27 1.27) (thickness 0.15)))
    )
    (property "Value" "USB-C_JAE_DX07S024JJ2" (at 188.595 92.71 0)
      (effects (font (size 1.27 1.27) (thickness 0.15)) hide)
    )
    (property "Footprint" "antmicro-footprints:USB-C_Receptacle_JAE_DX07S024JJ2" (at 238.76 100.33 0)
      (effects (font (size 1.27 1.27) (thickness 0.15)) (justify left bottom) hide)
    )
    (property "Datasheet" "https://www.jae.com/en/connectors/series/detail/product/id=66508" (at 238.76 102.87 0)
      (effects (font (size 1.27 1.27) (thickness 0.15)) (justify left bottom) hide)
    )
    (property "MPN" "DX07S024JJ2" (at 181.61 93.345 0)
      (effects (font (size 1.27 1.27) (thickness 0.15)) (justify left bottom))
    )
    (property "Manufacturer" "JAE Electronics" (at 238.76 107.95 0)
      (effects (font (size 1.27 1.27) (thickness 0.15)) (justify left bottom) hide)
    )
    (property "Author" "Antmicro" (at 238.76 110.49 0)
      (effects (font (size 1.27 1.27) (thickness 0.15)) (justify left bottom) hide)
    )
    (property "License" "Apache-2.0" (at 238.76 113.03 0)
      (effects (font (size 1.27 1.27) (thickness 0.15)) (justify left bottom) hide)
    )
    (pin "A1")
    (pin "A10")
    (pin "A11")
    (pin "A12")
    (pin "A2")
    (pin "A3")
    (pin "A4")
    (pin "A5")
    (pin "A6")
    (pin "A7")
    (pin "A8")
    (pin "A9")
    (pin "B1")
    (pin "B10")
    (pin "B11")
    (pin "B12")
    (pin "B2")
    (pin "B3")
    (pin "B4")
    (pin "B5")
    (pin "B6")
    (pin "B7")
    (pin "B8")
    (pin "B9")
    (pin "SH")
    (instances
      (project "thunderbolt-pcie-adapter"
        (path ""
          (reference "J1") (unit 1)
        )
      )
    )
  )

  (symbol (lib_id "antmicroCapacitors0402:C_100n_0402") (at 184.15 208.28 90) (unit 1)
    (in_bom yes) (on_board yes) (dnp no) (fields_autoplaced)
    (property "Reference" "C2" (at 184.785 203.835 90)
      (effects (font (size 1.27 1.27) (thickness 0.15)) (justify right))
    )
    (property "Value" "C_100n_0402" (at 194.31 187.96 0)
      (effects (font (size 1.27 1.27) (thickness 0.15)) (justify left bottom) hide)
    )
    (property "Footprint" "antmicro-footprints:C_0402_1005Metric" (at 196.85 187.96 0)
      (effects (font (size 1.27 1.27) (thickness 0.15)) (justify left bottom) hide)
    )
    (property "Datasheet" "https://www.murata.com/products/productdetail?partno=GRM155R61H104KE14%23" (at 199.39 187.96 0)
      (effects (font (size 1.27 1.27) (thickness 0.15)) (justify left bottom) hide)
    )
    (property "MPN" "GRM155R61H104KE14D" (at 201.93 187.96 0)
      (effects (font (size 1.27 1.27) (thickness 0.15)) (justify left bottom) hide)
    )
    (property "Manufacturer" "Murata" (at 204.47 187.96 0)
      (effects (font (size 1.27 1.27) (thickness 0.15)) (justify left bottom) hide)
    )
    (property "License" "Apache-2.0" (at 207.01 187.96 0)
      (effects (font (size 1.27 1.27) (thickness 0.15)) (justify left bottom) hide)
    )
    (property "Val" "100n" (at 189.23 207.01 90)
      (effects (font (size 1.27 1.27) (thickness 0.15)) (justify left bottom))
    )
    (property "Voltage" "50V" (at 212.09 187.96 0)
      (effects (font (size 1.27 1.27)) (justify left bottom) hide)
    )
    (property "Dielectric" "X5R" (at 214.63 187.96 0)
      (effects (font (size 1.27 1.27)) (justify left bottom) hide)
    )
    (property "Author" "Antmicro" (at 209.55 187.96 0)
      (effects (font (size 1.27 1.27) (thickness 0.15)) (justify left bottom) hide)
    )
    (pin "1")
    (pin "2")
    (instances
      (project "thunderbolt-pcie-adapter"
        (path ""
          (reference "C2") (unit 1)
        )
      )
    )
  )

  (symbol (lib_id "antmicropower:GND") (at 368.3 134.62 0) (unit 1)
    (in_bom yes) (on_board yes) (dnp no) (fields_autoplaced)
    (property "Reference" "#PWR012" (at 368.3 140.97 0)
      (effects (font (size 1.27 1.27)) hide)
    )
    (property "Value" "GND" (at 366.395 139.065 0)
      (effects (font (size 1.27 1.27) (thickness 0.15)) (justify left bottom))
    )
    (property "Footprint" "" (at 368.3 134.62 0)
      (effects (font (size 1.27 1.27) (thickness 0.15)) (justify left bottom) hide)
    )
    (property "Datasheet" "" (at 368.3 134.62 0)
      (effects (font (size 1.27 1.27) (thickness 0.15)) (justify left bottom) hide)
    )
    (property "Author" "Antmicro" (at 377.19 142.24 0)
      (effects (font (size 1.27 1.27) (thickness 0.15)) (justify left bottom) hide)
    )
    (property "License" "Apache-2.0" (at 377.19 144.78 0)
      (effects (font (size 1.27 1.27) (thickness 0.15)) (justify left bottom) hide)
    )
    (pin "1")
    (instances
      (project "thunderbolt-pcie-adapter"
        (path ""
          (reference "#PWR012") (unit 1)
        )
      )
    )
  )

  (symbol (lib_id "antmicropower:GND") (at 344.17 107.95 0) (unit 1)
    (in_bom yes) (on_board yes) (dnp no) (fields_autoplaced)
    (property "Reference" "#PWR011" (at 344.17 114.3 0)
      (effects (font (size 1.27 1.27)) hide)
    )
    (property "Value" "GND" (at 342.265 112.395 0)
      (effects (font (size 1.27 1.27) (thickness 0.15)) (justify left bottom))
    )
    (property "Footprint" "" (at 344.17 107.95 0)
      (effects (font (size 1.27 1.27) (thickness 0.15)) (justify left bottom) hide)
    )
    (property "Datasheet" "" (at 344.17 107.95 0)
      (effects (font (size 1.27 1.27) (thickness 0.15)) (justify left bottom) hide)
    )
    (property "Author" "Antmicro" (at 353.06 115.57 0)
      (effects (font (size 1.27 1.27) (thickness 0.15)) (justify left bottom) hide)
    )
    (property "License" "Apache-2.0" (at 353.06 118.11 0)
      (effects (font (size 1.27 1.27) (thickness 0.15)) (justify left bottom) hide)
    )
    (pin "1")
    (instances
      (project "thunderbolt-pcie-adapter"
        (path ""
          (reference "#PWR011") (unit 1)
        )
      )
    )
  )

  (symbol (lib_id "antmicroCapacitors0402:C_100n_0402") (at 190.5 208.28 90) (unit 1)
    (in_bom yes) (on_board yes) (dnp no) (fields_autoplaced)
    (property "Reference" "C3" (at 191.135 203.835 90)
      (effects (font (size 1.27 1.27) (thickness 0.15)) (justify right))
    )
    (property "Value" "C_100n_0402" (at 200.66 187.96 0)
      (effects (font (size 1.27 1.27) (thickness 0.15)) (justify left bottom) hide)
    )
    (property "Footprint" "antmicro-footprints:C_0402_1005Metric" (at 203.2 187.96 0)
      (effects (font (size 1.27 1.27) (thickness 0.15)) (justify left bottom) hide)
    )
    (property "Datasheet" "https://www.murata.com/products/productdetail?partno=GRM155R61H104KE14%23" (at 205.74 187.96 0)
      (effects (font (size 1.27 1.27) (thickness 0.15)) (justify left bottom) hide)
    )
    (property "MPN" "GRM155R61H104KE14D" (at 208.28 187.96 0)
      (effects (font (size 1.27 1.27) (thickness 0.15)) (justify left bottom) hide)
    )
    (property "Manufacturer" "Murata" (at 210.82 187.96 0)
      (effects (font (size 1.27 1.27) (thickness 0.15)) (justify left bottom) hide)
    )
    (property "License" "Apache-2.0" (at 213.36 187.96 0)
      (effects (font (size 1.27 1.27) (thickness 0.15)) (justify left bottom) hide)
    )
    (property "Val" "100n" (at 195.58 207.01 90)
      (effects (font (size 1.27 1.27) (thickness 0.15)) (justify left bottom))
    )
    (property "Voltage" "50V" (at 218.44 187.96 0)
      (effects (font (size 1.27 1.27)) (justify left bottom) hide)
    )
    (property "Dielectric" "X5R" (at 220.98 187.96 0)
      (effects (font (size 1.27 1.27)) (justify left bottom) hide)
    )
    (property "Author" "Antmicro" (at 215.9 187.96 0)
      (effects (font (size 1.27 1.27) (thickness 0.15)) (justify left bottom) hide)
    )
    (pin "1")
    (pin "2")
    (instances
      (project "thunderbolt-pcie-adapter"
        (path ""
          (reference "C3") (unit 1)
        )
      )
    )
  )

  (symbol (lib_id "antmicroMechanicalParts:MP_Pad6mm_Drill3mm") (at 31.75 270.51 0) (unit 1)
    (in_bom no) (on_board yes) (dnp no)
    (property "Reference" "MP2" (at 40.64 269.24 0)
      (effects (font (size 1.27 1.27) (thickness 0.15)) (justify left))
    )
    (property "Value" "MP_Pad6mm_Drill3mm" (at 40.64 271.78 0)
      (effects (font (size 1.27 1.27) (thickness 0.15)) (justify left))
    )
    (property "Footprint" "antmicro-footprints:MP_Pad6mm_Drill3mm" (at 52.07 278.13 0)
      (effects (font (size 1.27 1.27) (thickness 0.15)) (justify left bottom) hide)
    )
    (property "Datasheet" "" (at 48.59 286.08 0)
      (effects (font (size 1.27 1.27) (thickness 0.15)) (justify left bottom) hide)
    )
    (property "Author" "Antmicro" (at 52.07 280.67 0)
      (effects (font (size 1.27 1.27) (thickness 0.15)) (justify left bottom) hide)
    )
    (property "License" "Apache-2.0" (at 52.07 283.21 0)
      (effects (font (size 1.27 1.27) (thickness 0.15)) (justify left bottom) hide)
    )
    (pin "1")
    (instances
      (project "thunderbolt-pcie-adapter"
        (path ""
          (reference "MP2") (unit 1)
        )
      )
    )
  )

  (symbol (lib_id "antmicropower:GND") (at 196.85 210.82 0) (unit 1)
    (in_bom yes) (on_board yes) (dnp no) (fields_autoplaced)
    (property "Reference" "#PWR07" (at 196.85 217.17 0)
      (effects (font (size 1.27 1.27)) hide)
    )
    (property "Value" "GND" (at 194.945 215.265 0)
      (effects (font (size 1.27 1.27) (thickness 0.15)) (justify left bottom))
    )
    (property "Footprint" "" (at 196.85 210.82 0)
      (effects (font (size 1.27 1.27) (thickness 0.15)) (justify left bottom) hide)
    )
    (property "Datasheet" "" (at 196.85 210.82 0)
      (effects (font (size 1.27 1.27) (thickness 0.15)) (justify left bottom) hide)
    )
    (property "Author" "Antmicro" (at 205.74 218.44 0)
      (effects (font (size 1.27 1.27) (thickness 0.15)) (justify left bottom) hide)
    )
    (property "License" "Apache-2.0" (at 205.74 220.98 0)
      (effects (font (size 1.27 1.27) (thickness 0.15)) (justify left bottom) hide)
    )
    (pin "1")
    (instances
      (project "thunderbolt-pcie-adapter"
        (path ""
          (reference "#PWR07") (unit 1)
        )
      )
    )
  )

  (symbol (lib_id "antmicroWire2BoardConnectors:Molex_Nano-Fit_1x2_1053131102") (at 82.55 130.81 0) (mirror y) (unit 1)
    (in_bom yes) (on_board yes) (dnp no) (fields_autoplaced)
    (property "Reference" "J3" (at 78.74 124.46 0)
      (effects (font (size 1.27 1.27) (thickness 0.15)))
    )
    (property "Value" "Molex_Nano-Fit_1x2_1053131102" (at 69.215 135.89 0)
      (effects (font (size 1.27 1.27) (thickness 0.15)) (justify left bottom) hide)
    )
    (property "Footprint" "antmicro-footprints:Conn_Molex_Nano-Fit_1x2_1053131102" (at 69.215 138.43 0)
      (effects (font (size 1.27 1.27) (thickness 0.15)) (justify left bottom) hide)
    )
    (property "Datasheet" "https://tools.molex.com/pdm_docs/ps/PS-105300-100-001.pdf" (at 69.215 140.97 0)
      (effects (font (size 1.27 1.27) (thickness 0.15)) (justify left bottom) hide)
    )
    (property "Manufacturer" "Molex" (at 69.215 143.51 0)
      (effects (font (size 1.27 1.27) (thickness 0.15)) (justify left bottom) hide)
    )
    (property "MPN" "1053131102" (at 78.74 127 0)
      (effects (font (size 1.27 1.27) (thickness 0.15)))
    )
    (property "Author" "Antmicro" (at 69.215 148.59 0)
      (effects (font (size 1.27 1.27) (thickness 0.15)) (justify left bottom) hide)
    )
    (property "License" "Apache-2.0" (at 69.215 151.13 0)
      (effects (font (size 1.27 1.27) (thickness 0.15)) (justify left bottom) hide)
    )
    (pin "1")
    (pin "2")
    (instances
      (project "thunderbolt-pcie-adapter"
        (path ""
          (reference "J3") (unit 1)
        )
      )
    )
  )

  (symbol (lib_id "antmicropower:GND") (at 203.2 210.82 0) (unit 1)
    (in_bom yes) (on_board yes) (dnp no) (fields_autoplaced)
    (property "Reference" "#PWR08" (at 203.2 217.17 0)
      (effects (font (size 1.27 1.27)) hide)
    )
    (property "Value" "GND" (at 201.295 215.265 0)
      (effects (font (size 1.27 1.27) (thickness 0.15)) (justify left bottom))
    )
    (property "Footprint" "" (at 203.2 210.82 0)
      (effects (font (size 1.27 1.27) (thickness 0.15)) (justify left bottom) hide)
    )
    (property "Datasheet" "" (at 203.2 210.82 0)
      (effects (font (size 1.27 1.27) (thickness 0.15)) (justify left bottom) hide)
    )
    (property "Author" "Antmicro" (at 212.09 218.44 0)
      (effects (font (size 1.27 1.27) (thickness 0.15)) (justify left bottom) hide)
    )
    (property "License" "Apache-2.0" (at 212.09 220.98 0)
      (effects (font (size 1.27 1.27) (thickness 0.15)) (justify left bottom) hide)
    )
    (pin "1")
    (instances
      (project "thunderbolt-pcie-adapter"
        (path ""
          (reference "#PWR08") (unit 1)
        )
      )
    )
  )

  (symbol (lib_id "antmicropower:GND") (at 30.48 279.4 0) (unit 1)
    (in_bom yes) (on_board yes) (dnp no) (fields_autoplaced)
    (property "Reference" "#PWR03" (at 39.37 281.94 0)
      (effects (font (size 1.27 1.27) (thickness 0.15)) (justify left bottom) hide)
    )
    (property "Value" "GND" (at 30.48 283.845 0)
      (effects (font (size 1.27 1.27) (thickness 0.15)))
    )
    (property "Footprint" "" (at 39.37 287.02 0)
      (effects (font (size 1.27 1.27) (thickness 0.15)) (justify left bottom) hide)
    )
    (property "Datasheet" "" (at 39.37 292.1 0)
      (effects (font (size 1.27 1.27) (thickness 0.15)) (justify left bottom) hide)
    )
    (property "Author" "Antmicro" (at 39.37 287.02 0)
      (effects (font (size 1.27 1.27) (thickness 0.15)) (justify left bottom) hide)
    )
    (property "License" "Apache-2.0" (at 39.37 289.56 0)
      (effects (font (size 1.27 1.27) (thickness 0.15)) (justify left bottom) hide)
    )
    (pin "1")
    (instances
      (project "thunderbolt-pcie-adapter"
        (path ""
          (reference "#PWR03") (unit 1)
        )
      )
    )
  )

  (symbol (lib_id "antmicroPciConnectors:PCIe_x4_Conn_EdgeMount_Open") (at 297.18 100.33 0) (unit 1)
    (in_bom yes) (on_board yes) (dnp no) (fields_autoplaced)
    (property "Reference" "J2" (at 313.69 92.71 0)
      (effects (font (size 1.27 1.27) (thickness 0.15)))
    )
    (property "Value" "PCIe_x4_Conn_EdgeMount_Open" (at 345.44 105.41 0)
      (effects (font (size 1.27 1.27) (thickness 0.15)) (justify left bottom) hide)
    )
    (property "Footprint" "antmicro-footprints:PCIE_TE_2-2387405-2" (at 345.44 107.95 0)
      (effects (font (size 1.27 1.27) (thickness 0.15)) (justify left bottom) hide)
    )
    (property "Datasheet" "https://www.te.com/commerce/DocumentDelivery/DDEController?Action=showdoc&DocId=Customer+Drawing%7F2387405%7FA%7Fpdf%7FEnglish%7FENG_CD_2387405_A.pdf%7F2-2387405-2" (at 345.44 110.49 0)
      (effects (font (size 1.27 1.27) (thickness 0.15)) (justify left bottom) hide)
    )
    (property "MPN" "2-2387405-2" (at 313.69 95.25 0)
      (effects (font (size 1.27 1.27) (thickness 0.15)))
    )
    (property "Manufacturer" "TE Connectivity" (at 345.44 115.57 0)
      (effects (font (size 1.27 1.27) (thickness 0.15)) (justify left bottom) hide)
    )
    (property "Author" "Antmicro" (at 345.44 118.11 0)
      (effects (font (size 1.27 1.27) (thickness 0.15)) (justify left bottom) hide)
    )
    (property "License" "Apache-2.0" (at 345.44 120.65 0)
      (effects (font (size 1.27 1.27) (thickness 0.15)) (justify left bottom) hide)
    )
    (pin "A1")
    (pin "A10")
    (pin "A11")
    (pin "A12")
    (pin "A13")
    (pin "A14")
    (pin "A15")
    (pin "A16")
    (pin "A17")
    (pin "A18")
    (pin "A19")
    (pin "A2")
    (pin "A20")
    (pin "A21")
    (pin "A22")
    (pin "A23")
    (pin "A24")
    (pin "A25")
    (pin "A26")
    (pin "A27")
    (pin "A28")
    (pin "A29")
    (pin "A3")
    (pin "A30")
    (pin "A31")
    (pin "A32")
    (pin "A4")
    (pin "A5")
    (pin "A6")
    (pin "A7")
    (pin "A8")
    (pin "A9")
    (pin "B1")
    (pin "B10")
    (pin "B11")
    (pin "B12")
    (pin "B13")
    (pin "B14")
    (pin "B15")
    (pin "B16")
    (pin "B17")
    (pin "B18")
    (pin "B19")
    (pin "B2")
    (pin "B20")
    (pin "B21")
    (pin "B22")
    (pin "B23")
    (pin "B24")
    (pin "B25")
    (pin "B26")
    (pin "B27")
    (pin "B28")
    (pin "B29")
    (pin "B3")
    (pin "B30")
    (pin "B31")
    (pin "B32")
    (pin "B4")
    (pin "B5")
    (pin "B6")
    (pin "B7")
    (pin "B8")
    (pin "B9")
    (instances
      (project "thunderbolt-pcie-adapter"
        (path ""
          (reference "J2") (unit 1)
        )
      )
    )
  )

  (symbol (lib_id "antmicroMechanicalParts:MP_Pad6mm_Drill3mm") (at 31.75 276.86 0) (unit 1)
    (in_bom no) (on_board yes) (dnp no)
    (property "Reference" "MP3" (at 40.64 275.59 0)
      (effects (font (size 1.27 1.27) (thickness 0.15)) (justify left))
    )
    (property "Value" "MP_Pad6mm_Drill3mm" (at 40.64 278.13 0)
      (effects (font (size 1.27 1.27) (thickness 0.15)) (justify left))
    )
    (property "Footprint" "antmicro-footprints:MP_Pad6mm_Drill3mm" (at 52.07 284.48 0)
      (effects (font (size 1.27 1.27) (thickness 0.15)) (justify left bottom) hide)
    )
    (property "Datasheet" "" (at 48.59 292.43 0)
      (effects (font (size 1.27 1.27) (thickness 0.15)) (justify left bottom) hide)
    )
    (property "Author" "Antmicro" (at 52.07 287.02 0)
      (effects (font (size 1.27 1.27) (thickness 0.15)) (justify left bottom) hide)
    )
    (property "License" "Apache-2.0" (at 52.07 289.56 0)
      (effects (font (size 1.27 1.27) (thickness 0.15)) (justify left bottom) hide)
    )
    (pin "1")
    (instances
      (project "thunderbolt-pcie-adapter"
        (path ""
          (reference "MP3") (unit 1)
        )
      )
    )
  )

  (symbol (lib_id "antmicropower:GND") (at 85.09 135.89 0) (unit 1)
    (in_bom yes) (on_board yes) (dnp no)
    (property "Reference" "#PWR0146" (at 85.09 142.24 0)
      (effects (font (size 1.27 1.27)) hide)
    )
    (property "Value" "GND" (at 83.185 140.335 0)
      (effects (font (size 1.27 1.27) (thickness 0.15)) (justify left bottom))
    )
    (property "Footprint" "" (at 85.09 135.89 0)
      (effects (font (size 1.27 1.27) (thickness 0.15)) (justify left bottom) hide)
    )
    (property "Datasheet" "" (at 85.09 135.89 0)
      (effects (font (size 1.27 1.27) (thickness 0.15)) (justify left bottom) hide)
    )
    (property "Author" "Antmicro" (at 93.98 143.51 0)
      (effects (font (size 1.27 1.27) (thickness 0.15)) (justify left bottom) hide)
    )
    (property "License" "Apache-2.0" (at 93.98 146.05 0)
      (effects (font (size 1.27 1.27) (thickness 0.15)) (justify left bottom) hide)
    )
    (pin "1")
    (instances
      (project "thunderbolt-pcie-adapter"
        (path ""
          (reference "#PWR0146") (unit 1)
        )
      )
    )
  )

  (symbol (lib_id "antmicropower:GND") (at 184.15 210.82 0) (unit 1)
    (in_bom yes) (on_board yes) (dnp no)
    (property "Reference" "#PWR04" (at 184.15 217.17 0)
      (effects (font (size 1.27 1.27)) hide)
    )
    (property "Value" "GND" (at 182.245 215.265 0)
      (effects (font (size 1.27 1.27) (thickness 0.15)) (justify left bottom))
    )
    (property "Footprint" "" (at 184.15 210.82 0)
      (effects (font (size 1.27 1.27) (thickness 0.15)) (justify left bottom) hide)
    )
    (property "Datasheet" "" (at 184.15 210.82 0)
      (effects (font (size 1.27 1.27) (thickness 0.15)) (justify left bottom) hide)
    )
    (property "Author" "Antmicro" (at 193.04 218.44 0)
      (effects (font (size 1.27 1.27) (thickness 0.15)) (justify left bottom) hide)
    )
    (property "License" "Apache-2.0" (at 193.04 220.98 0)
      (effects (font (size 1.27 1.27) (thickness 0.15)) (justify left bottom) hide)
    )
    (pin "1")
    (instances
      (project "thunderbolt-pcie-adapter"
        (path ""
          (reference "#PWR04") (unit 1)
        )
      )
    )
  )

  (symbol (lib_id "antmicropower:GND") (at 331.47 187.96 0) (unit 1)
    (in_bom yes) (on_board yes) (dnp no) (fields_autoplaced)
    (property "Reference" "#PWR010" (at 331.47 194.31 0)
      (effects (font (size 1.27 1.27)) hide)
    )
    (property "Value" "GND" (at 329.565 192.405 0)
      (effects (font (size 1.27 1.27) (thickness 0.15)) (justify left bottom))
    )
    (property "Footprint" "" (at 331.47 187.96 0)
      (effects (font (size 1.27 1.27) (thickness 0.15)) (justify left bottom) hide)
    )
    (property "Datasheet" "" (at 331.47 187.96 0)
      (effects (font (size 1.27 1.27) (thickness 0.15)) (justify left bottom) hide)
    )
    (property "Author" "Antmicro" (at 340.36 195.58 0)
      (effects (font (size 1.27 1.27) (thickness 0.15)) (justify left bottom) hide)
    )
    (property "License" "Apache-2.0" (at 340.36 198.12 0)
      (effects (font (size 1.27 1.27) (thickness 0.15)) (justify left bottom) hide)
    )
    (pin "1")
    (instances
      (project "thunderbolt-pcie-adapter"
        (path ""
          (reference "#PWR010") (unit 1)
        )
      )
    )
  )

  (symbol (lib_id "antmicroCapacitors0402:C_100n_0402") (at 203.2 208.28 90) (unit 1)
    (in_bom yes) (on_board yes) (dnp no) (fields_autoplaced)
    (property "Reference" "C5" (at 203.835 203.835 90)
      (effects (font (size 1.27 1.27) (thickness 0.15)) (justify right))
    )
    (property "Value" "C_100n_0402" (at 213.36 187.96 0)
      (effects (font (size 1.27 1.27) (thickness 0.15)) (justify left bottom) hide)
    )
    (property "Footprint" "antmicro-footprints:C_0402_1005Metric" (at 215.9 187.96 0)
      (effects (font (size 1.27 1.27) (thickness 0.15)) (justify left bottom) hide)
    )
    (property "Datasheet" "https://www.murata.com/products/productdetail?partno=GRM155R61H104KE14%23" (at 218.44 187.96 0)
      (effects (font (size 1.27 1.27) (thickness 0.15)) (justify left bottom) hide)
    )
    (property "MPN" "GRM155R61H104KE14D" (at 220.98 187.96 0)
      (effects (font (size 1.27 1.27) (thickness 0.15)) (justify left bottom) hide)
    )
    (property "Manufacturer" "Murata" (at 223.52 187.96 0)
      (effects (font (size 1.27 1.27) (thickness 0.15)) (justify left bottom) hide)
    )
    (property "License" "Apache-2.0" (at 226.06 187.96 0)
      (effects (font (size 1.27 1.27) (thickness 0.15)) (justify left bottom) hide)
    )
    (property "Val" "100n" (at 208.915 207.01 90)
      (effects (font (size 1.27 1.27) (thickness 0.15)) (justify left bottom))
    )
    (property "Voltage" "50V" (at 231.14 187.96 0)
      (effects (font (size 1.27 1.27)) (justify left bottom) hide)
    )
    (property "Dielectric" "X5R" (at 233.68 187.96 0)
      (effects (font (size 1.27 1.27)) (justify left bottom) hide)
    )
    (property "Author" "Antmicro" (at 228.6 187.96 0)
      (effects (font (size 1.27 1.27) (thickness 0.15)) (justify left bottom) hide)
    )
    (pin "1")
    (pin "2")
    (instances
      (project "thunderbolt-pcie-adapter"
        (path ""
          (reference "C5") (unit 1)
        )
      )
    )
  )

  (symbol (lib_id "antmicroCapacitorsmisc:C_10u_0805_35V") (at 283.21 105.41 90) (unit 1)
    (in_bom yes) (on_board yes) (dnp no) (fields_autoplaced)
    (property "Reference" "C1" (at 285.115 101.6 90)
      (effects (font (size 1.27 1.27) (thickness 0.15)) (justify right))
    )
    (property "Value" "C_10u_0805_35V" (at 293.37 85.09 0)
      (effects (font (size 1.27 1.27) (thickness 0.15)) (justify left bottom) hide)
    )
    (property "Footprint" "antmicro-footprints:C_0805_2012Metric" (at 295.91 85.09 0)
      (effects (font (size 1.27 1.27) (thickness 0.15)) (justify left bottom) hide)
    )
    (property "Datasheet" "https://www.murata.com/products/productdetail?partno=GRM21BR6YA106KE43%23" (at 298.45 85.09 0)
      (effects (font (size 1.27 1.27) (thickness 0.15)) (justify left bottom) hide)
    )
    (property "MPN" "GRM21BR6YA106KE43L" (at 300.99 85.09 0)
      (effects (font (size 1.27 1.27) (thickness 0.15)) (justify left bottom) hide)
    )
    (property "Manufacturer" "Murata" (at 303.53 85.09 0)
      (effects (font (size 1.27 1.27) (thickness 0.15)) (justify left bottom) hide)
    )
    (property "License" "Apache-2.0" (at 306.07 85.09 0)
      (effects (font (size 1.27 1.27) (thickness 0.15)) (justify left bottom) hide)
    )
    (property "Val" "10u" (at 288.925 102.87 90)
      (effects (font (size 1.27 1.27) (thickness 0.15)) (justify left bottom))
    )
    (property "Voltage" "35V" (at 311.15 85.09 0)
      (effects (font (size 1.27 1.27)) (justify left bottom) hide)
    )
    (property "Dielectric" "" (at 313.69 85.09 0)
      (effects (font (size 1.27 1.27)) (justify left bottom) hide)
    )
    (property "Author" "Antmicro" (at 308.61 85.09 0)
      (effects (font (size 1.27 1.27) (thickness 0.15)) (justify left bottom) hide)
    )
    (pin "1")
    (pin "2")
    (instances
      (project "thunderbolt-pcie-adapter"
        (path ""
          (reference "C1") (unit 1)
        )
      )
    )
  )

  (symbol (lib_id "antmicropower:PWR_FLAG") (at 101.6 129.54 0) (unit 1)
    (in_bom yes) (on_board yes) (dnp no)
    (property "Reference" "#FLG0108" (at 101.6 127.635 0)
      (effects (font (size 1.27 1.27)) hide)
    )
    (property "Value" "PWR_FLAG" (at 101.6 125.73 0)
      (effects (font (size 1.27 1.27)))
    )
    (property "Footprint" "" (at 101.6 129.54 0)
      (effects (font (size 1.27 1.27)) hide)
    )
    (property "Datasheet" "" (at 101.6 129.54 0)
      (effects (font (size 1.27 1.27)) hide)
    )
    (pin "1")
    (instances
      (project "thunderbolt-pcie-adapter"
        (path ""
          (reference "#FLG0108") (unit 1)
        )
      )
    )
  )

  (symbol (lib_id "antmicroResistors0402:R_3k3_0402") (at 368.3 133.35 90) (unit 1)
    (in_bom yes) (on_board yes) (dnp no) (fields_autoplaced)
    (property "Reference" "R1" (at 370.205 129.54 90)
      (effects (font (size 1.27 1.27) (thickness 0.15)) (justify right))
    )
    (property "Value" "R_3k3_0402" (at 381 113.03 0)
      (effects (font (size 1.27 1.27) (thickness 0.15)) (justify left bottom) hide)
    )
    (property "Footprint" "antmicro-footprints:R_0402_1005Metric" (at 383.54 113.03 0)
      (effects (font (size 1.27 1.27) (thickness 0.15)) (justify left bottom) hide)
    )
    (property "Datasheet" "https://www.bourns.com/docs/product-datasheets/cr.pdf" (at 386.08 113.03 0)
      (effects (font (size 1.27 1.27) (thickness 0.15)) (justify left bottom) hide)
    )
    (property "MPN" "CR0402-FX-3301GLF" (at 388.62 113.03 0)
      (effects (font (size 1.27 1.27) (thickness 0.15)) (justify left bottom) hide)
    )
    (property "Manufacturer" "Bourns" (at 391.16 113.03 0)
      (effects (font (size 1.27 1.27) (thickness 0.15)) (justify left bottom) hide)
    )
    (property "License" "Apache-2.0" (at 393.7 113.03 0)
      (effects (font (size 1.27 1.27) (thickness 0.15)) (justify left bottom) hide)
    )
    (property "Val" "3k3" (at 370.205 132.08 90)
      (effects (font (size 1.27 1.27) (thickness 0.15)) (justify right))
    )
    (property "Tolerance" "1%" (at 378.46 113.03 0)
      (effects (font (size 1.27 1.27)) (justify left bottom) hide)
    )
    (property "Author" "Antmicro" (at 396.24 113.03 0)
      (effects (font (size 1.27 1.27) (thickness 0.15)) (justify left bottom) hide)
    )
    (pin "1")
    (pin "2")
    (instances
      (project "thunderbolt-pcie-adapter"
        (path ""
          (reference "R1") (unit 1)
        )
      )
    )
  )

  (symbol (lib_id "antmicroCapacitors0402:C_100n_0402") (at 196.85 208.28 90) (unit 1)
    (in_bom yes) (on_board yes) (dnp no) (fields_autoplaced)
    (property "Reference" "C4" (at 197.485 203.835 90)
      (effects (font (size 1.27 1.27) (thickness 0.15)) (justify right))
    )
    (property "Value" "C_100n_0402" (at 207.01 187.96 0)
      (effects (font (size 1.27 1.27) (thickness 0.15)) (justify left bottom) hide)
    )
    (property "Footprint" "antmicro-footprints:C_0402_1005Metric" (at 209.55 187.96 0)
      (effects (font (size 1.27 1.27) (thickness 0.15)) (justify left bottom) hide)
    )
    (property "Datasheet" "https://www.murata.com/products/productdetail?partno=GRM155R61H104KE14%23" (at 212.09 187.96 0)
      (effects (font (size 1.27 1.27) (thickness 0.15)) (justify left bottom) hide)
    )
    (property "MPN" "GRM155R61H104KE14D" (at 214.63 187.96 0)
      (effects (font (size 1.27 1.27) (thickness 0.15)) (justify left bottom) hide)
    )
    (property "Manufacturer" "Murata" (at 217.17 187.96 0)
      (effects (font (size 1.27 1.27) (thickness 0.15)) (justify left bottom) hide)
    )
    (property "License" "Apache-2.0" (at 219.71 187.96 0)
      (effects (font (size 1.27 1.27) (thickness 0.15)) (justify left bottom) hide)
    )
    (property "Val" "100n" (at 201.93 207.01 90)
      (effects (font (size 1.27 1.27) (thickness 0.15)) (justify left bottom))
    )
    (property "Voltage" "50V" (at 224.79 187.96 0)
      (effects (font (size 1.27 1.27)) (justify left bottom) hide)
    )
    (property "Dielectric" "X5R" (at 227.33 187.96 0)
      (effects (font (size 1.27 1.27)) (justify left bottom) hide)
    )
    (property "Author" "Antmicro" (at 222.25 187.96 0)
      (effects (font (size 1.27 1.27) (thickness 0.15)) (justify left bottom) hide)
    )
    (pin "1")
    (pin "2")
    (instances
      (project "thunderbolt-pcie-adapter"
        (path ""
          (reference "C4") (unit 1)
        )
      )
    )
  )

  (symbol (lib_id "antmicropower:GND") (at 201.93 173.99 0) (mirror y) (unit 1)
    (in_bom yes) (on_board yes) (dnp no)
    (property "Reference" "#PWR038" (at 201.93 180.34 0)
      (effects (font (size 1.27 1.27)) hide)
    )
    (property "Value" "GND" (at 203.835 179.07 0)
      (effects (font (size 1.27 1.27) (thickness 0.15)) (justify left bottom))
    )
    (property "Footprint" "" (at 201.93 173.99 0)
      (effects (font (size 1.27 1.27) (thickness 0.15)) (justify left bottom) hide)
    )
    (property "Datasheet" "" (at 201.93 173.99 0)
      (effects (font (size 1.27 1.27) (thickness 0.15)) (justify left bottom) hide)
    )
    (property "Author" "Antmicro" (at 193.04 181.61 0)
      (effects (font (size 1.27 1.27) (thickness 0.15)) (justify left bottom) hide)
    )
    (property "License" "Apache-2.0" (at 193.04 184.15 0)
      (effects (font (size 1.27 1.27) (thickness 0.15)) (justify left bottom) hide)
    )
    (pin "1")
    (instances
      (project "thunderbolt-pcie-adapter"
        (path ""
          (reference "#PWR038") (unit 1)
        )
      )
    )
  )
)
